# SCM (Grand Teton) — schematic netlist excerpt (pin names and nets, part order shuffled) for the footprints in the layout excerpt that follows; sources: Cadence DE-HDL packaged netlist, KiCad conversion of 12092022_DA0F0TMDCD0_F0T_Management_Board_D_brd_V3_OCP.brd

R725  Q_RES  33.2 1% CHIP  pkg 0402LF  page 44 : A = SPI_BMC_BIOS_ROM_IO3 ; B = SPI_BMC_BIOS_ROM_R_IO3
R833  Q_RES  33.2 1% CHIP  pkg 0402LF  page 35 : A = FM_ESPI_PLD_EN ; B = FM_ESPI_PLD_R_EN

(kicad_pcb
	(version 20260206)
	(generator "pcbnew")
	(generator_version "10.0")
	(general
		(thickness 1.6)
		(legacy_teardrops no)
	)
	(paper "A4")
	(title_block
		(title "12092022_DA0F0TMDCD0_F0T_Management_Board_D_brd_V3_OCP.brd")
		(comment 1 "Grand Teton / footprints 1023-1024 of 1440")
	)
	(layers
		(0 "F.Cu" signal "TOP")
		(4 "In1.Cu" signal "GND")
		(6 "In2.Cu" signal "IN1")
		(8 "In3.Cu" signal "GND1")
		(10 "In4.Cu" signal "IN2")
		(12 "In5.Cu" signal "VCC")
		(14 "In6.Cu" signal "VCC1")
		(16 "In7.Cu" signal "IN3")
		(18 "In8.Cu" signal "GND2")
		(20 "In9.Cu" signal "IN4")
		(22 "In10.Cu" signal "GND3")
		(2 "B.Cu" signal "BOTTOM")
		(9 "F.Adhes" user "F.Adhesive")
		(11 "B.Adhes" user "B.Adhesive")
		(13 "F.Paste" user "Package Geometry/Pastemask Top")
		(15 "B.Paste" user "Package Geometry/Pastemask Bottom")
		(5 "F.SilkS" user "Ref Des/Silkscreen Top")
		(7 "B.SilkS" user "Ref Des/Silkscreen Bottom")
		(1 "F.Mask" user "Board Geometry/Soldermask Top")
		(3 "B.Mask" user "Board Geometry/Soldermask Bottom")
		(17 "Dwgs.User" user "User.Drawings")
		(19 "Cmts.User" user "User.Comments")
		(21 "Eco1.User" user "User.Eco1")
		(23 "Eco2.User" user "User.Eco2")
		(25 "Edge.Cuts" user "Board Geometry/Outline")
		(27 "Margin" user)
		(31 "F.CrtYd" user "Package Geometry/Place Bound Top")
		(29 "B.CrtYd" user "Package Geometry/Place Bound Bottom")
		(35 "F.Fab" user "Ref Des/Assembly Top")
		(33 "B.Fab" user "Ref Des/Assembly Bottom")
	)
	(footprint ""
		(layer "B.Cu")
		(at 12.319 -88.392 180)
		(property "Reference" "R833"
			(at 0 0 0)
			(layer "B.SilkS")
			(hide yes)
			(effects
				(font
					(size 1.27 1.27)
				)
				(justify mirror)
			)
		)
		(property "Value" ""
			(at 0 0 0)
			(layer "B.Fab")
			(effects
				(font
					(size 1.27 1.27)
				)
				(justify mirror)
			)
		)
		(duplicate_pad_numbers_are_jumpers no)
		(fp_line
			(start 0.7874 0.4064)
			(end 0.7874 -0.4064)
			(stroke
				(width 0.1524)
				(type default)
			)
			(layer "B.SilkS")
		)
		(fp_line
			(start 0.7874 -0.4064)
			(end -0.7874 -0.4064)
			(stroke
				(width 0.1524)
				(type default)
			)
			(layer "B.SilkS")
		)
		(fp_line
			(start -0.7874 0.4064)
			(end 0.7874 0.4064)
			(stroke
				(width 0.1524)
				(type default)
			)
			(layer "B.SilkS")
		)
		(fp_line
			(start -0.7874 -0.4064)
			(end -0.7874 0.4064)
			(stroke
				(width 0.1524)
				(type default)
			)
			(layer "B.SilkS")
		)
		(fp_line
			(start 0.67945 0.3048)
			(end 0.67945 -0.305054)
			(stroke
				(width 0.1)
				(type default)
			)
			(layer "B.Fab")
		)
		(fp_line
			(start 0.67945 -0.305054)
			(end 0.12065 -0.305054)
			(stroke
				(width 0.1)
				(type default)
			)
			(layer "B.Fab")
		)
		(fp_line
			(start 0.12065 0.3048)
			(end 0.67945 0.3048)
			(stroke
				(width 0.1)
				(type default)
			)
			(layer "B.Fab")
		)
		(fp_line
			(start 0.12065 0.2794)
			(end 0.12065 0.3048)
			(stroke
				(width 0.1)
				(type default)
			)
			(layer "B.Fab")
		)
		(fp_line
			(start 0.12065 -0.2794)
			(end -0.12065 -0.2794)
			(stroke
				(width 0.1)
				(type default)
			)
			(layer "B.Fab")
		)
		(fp_line
			(start 0.12065 -0.305054)
			(end 0.12065 -0.2794)
			(stroke
				(width 0.1)
				(type default)
			)
			(layer "B.Fab")
		)
		(fp_line
			(start -0.120396 0.3048)
			(end -0.120396 0.2794)
			(stroke
				(width 0.1)
				(type default)
			)
			(layer "B.Fab")
		)
		(fp_line
			(start -0.120396 0.2794)
			(end 0.12065 0.2794)
			(stroke
				(width 0.1)
				(type default)
			)
			(layer "B.Fab")
		)
		(fp_line
			(start -0.12065 -0.2794)
			(end -0.12065 -0.3048)
			(stroke
				(width 0.1)
				(type default)
			)
			(layer "B.Fab")
		)
		(fp_line
			(start -0.12065 -0.3048)
			(end -0.67945 -0.3048)
			(stroke
				(width 0.1)
				(type default)
			)
			(layer "B.Fab")
		)
		(fp_line
			(start -0.67945 0.3048)
			(end -0.120396 0.3048)
			(stroke
				(width 0.1)
				(type default)
			)
			(layer "B.Fab")
		)
		(fp_line
			(start -0.67945 -0.3048)
			(end -0.67945 0.3048)
			(stroke
				(width 0.1)
				(type default)
			)
			(layer "B.Fab")
		)
		(pad "1" smd circle
			(at 0.40005 0)
			(size 0 0)
			(layers "B.Cu" "B.Mask" "B.Paste")
			(net "FM_ESPI_PLD_EN")
		)
		(pad "2" smd circle
			(at -0.40005 0)
			(size 0 0)
			(layers "B.Cu" "B.Mask" "B.Paste")
			(net "FM_ESPI_PLD_R_EN")
		)
	)
	(footprint ""
		(layer "B.Cu")
		(at 60.7314 -64.0588 -90)
		(property "Reference" "R725"
			(at 0 0 90)
			(layer "B.SilkS")
			(hide yes)
			(effects
				(font
					(size 1.27 1.27)
				)
				(justify mirror)
			)
		)
		(property "Value" ""
			(at 0 0 90)
			(layer "B.Fab")
			(effects
				(font
					(size 1.27 1.27)
				)
				(justify mirror)
			)
		)
		(duplicate_pad_numbers_are_jumpers no)
		(fp_line
			(start -0.7874 0.4064)
			(end 0.7874 0.4064)
			(stroke
				(width 0.1524)
				(type default)
			)
			(layer "B.SilkS")
		)
		(fp_line
			(start 0.7874 0.4064)
			(end 0.7874 -0.4064)
			(stroke
				(width 0.1524)
				(type default)
			)
			(layer "B.SilkS")
		)
		(fp_line
			(start -0.7874 -0.4064)
			(end -0.7874 0.4064)
			(stroke
				(width 0.1524)
				(type default)
			)
			(layer "B.SilkS")
		)
		(fp_line
			(start 0.7874 -0.4064)
			(end -0.7874 -0.4064)
			(stroke
				(width 0.1524)
				(type default)
			)
			(layer "B.SilkS")
		)
		(fp_line
			(start -0.67945 0.3048)
			(end -0.120396 0.3048)
			(stroke
				(width 0.1)
				(type default)
			)
			(layer "B.Fab")
		)
		(fp_line
			(start -0.120396 0.3048)
			(end -0.120396 0.2794)
			(stroke
				(width 0.1)
				(type default)
			)
			(layer "B.Fab")
		)
		(fp_line
			(start 0.12065 0.3048)
			(end 0.67945 0.3048)
			(stroke
				(width 0.1)
				(type default)
			)
			(layer "B.Fab")
		)
		(fp_line
			(start 0.67945 0.3048)
			(end 0.67945 -0.305054)
			(stroke
				(width 0.1)
				(type default)
			)
			(layer "B.Fab")
		)
		(fp_line
			(start -0.120396 0.2794)
			(end 0.12065 0.2794)
			(stroke
				(width 0.1)
				(type default)
			)
			(layer "B.Fab")
		)
		(fp_line
			(start 0.12065 0.2794)
			(end 0.12065 0.3048)
			(stroke
				(width 0.1)
				(type default)
			)
			(layer "B.Fab")
		)
		(fp_line
			(start -0.12065 -0.2794)
			(end -0.12065 -0.3048)
			(stroke
				(width 0.1)
				(type default)
			)
			(layer "B.Fab")
		)
		(fp_line
			(start 0.12065 -0.2794)
			(end -0.12065 -0.2794)
			(stroke
				(width 0.1)
				(type default)
			)
			(layer "B.Fab")
		)
		(fp_line
			(start -0.67945 -0.3048)
			(end -0.67945 0.3048)
			(stroke
				(width 0.1)
				(type default)
			)
			(layer "B.Fab")
		)
		(fp_line
			(start -0.12065 -0.3048)
			(end -0.67945 -0.3048)
			(stroke
				(width 0.1)
				(type default)
			)
			(layer "B.Fab")
		)
		(fp_line
			(start 0.12065 -0.305054)
			(end 0.12065 -0.2794)
			(stroke
				(width 0.1)
				(type default)
			)
			(layer "B.Fab")
		)
		(fp_line
			(start 0.67945 -0.305054)
			(end 0.12065 -0.305054)
			(stroke
				(width 0.1)
				(type default)
			)
			(layer "B.Fab")
		)
		(pad "1" smd circle
			(at 0.40005 0 90)
			(size 0 0)
			(layers "B.Cu" "B.Mask" "B.Paste")
			(net "SPI_BMC_BIOS_ROM_IO3")
		)
		(pad "2" smd circle
			(at -0.40005 0 90)
			(size 0 0)
			(layers "B.Cu" "B.Mask" "B.Paste")
			(net "SPI_BMC_BIOS_ROM_R_IO3")
		)
	)
)
